(kicad_pcb
	(version 20260206)
	(generator "pcbnew")
	(generator_version "10.0")
	(general
		(thickness 1.6)
		(legacy_teardrops no)
	)
	(paper "A4")
	(title_block
		(title "Wiwynn_Tioga_Pass_MB.brd")
		(comment 1 "Tioga Pass / footprints 4107-4113 of 4770")
	)
	(layers
		(0 "F.Cu" signal "TOP")
		(4 "In1.Cu" signal "L2GND")
		(6 "In2.Cu" signal "L3")
		(8 "In3.Cu" signal "L4GND")
		(10 "In4.Cu" signal "L5")
		(12 "In5.Cu" signal "L6GND")
		(14 "In6.Cu" signal "L7VCC")
		(16 "In7.Cu" signal "L8VCC")
		(18 "In8.Cu" signal "L9GND")
		(20 "In9.Cu" signal "L10")
		(22 "In10.Cu" signal "L11GND")
		(24 "In11.Cu" signal "L12")
		(26 "In12.Cu" signal "L13GND")
		(2 "B.Cu" signal "BOTTOM")
		(9 "F.Adhes" user "F.Adhesive")
		(11 "B.Adhes" user "B.Adhesive")
		(13 "F.Paste" user "Package Geometry/Pastemask Top")
		(15 "B.Paste" user "Package Geometry/Pastemask Bottom")
		(5 "F.SilkS" user "Ref Des/Silkscreen Top")
		(7 "B.SilkS" user "Ref Des/Silkscreen Bottom")
		(1 "F.Mask" user "Board Geometry/Soldermask Top")
		(3 "B.Mask" user "Board Geometry/Soldermask Bottom")
		(17 "Dwgs.User" user "User.Drawings")
		(19 "Cmts.User" user "User.Comments")
		(21 "Eco1.User" user "User.Eco1")
		(23 "Eco2.User" user "User.Eco2")
		(25 "Edge.Cuts" user "Board Geometry/Outline")
		(27 "Margin" user)
		(31 "F.CrtYd" user "Package Geometry/Place Bound Top")
		(29 "B.CrtYd" user "Package Geometry/Place Bound Bottom")
		(35 "F.Fab" user "Ref Des/Assembly Top")
		(33 "B.Fab" user "Ref Des/Assembly Bottom")
	)
	(footprint ""
		(layer "B.Cu")
		(at 398.4244 -88.2777)
		(property "Reference" "R8D7"
			(at 0 0 0)
			(layer "B.SilkS")
			(hide yes)
			(effects
				(font
					(size 1.27 1.27)
				)
				(justify mirror)
			)
		)
		(property "Value" ""
			(at 0 0 0)
			(layer "B.Fab")
			(effects
				(font
					(size 1.27 1.27)
				)
				(justify mirror)
			)
		)
		(duplicate_pad_numbers_are_jumpers no)
		(fp_poly
			(pts
				(xy 0.2794 -0.1016) (xy -0.2794 -0.1016) (xy -0.2794 0.9906) (xy 0.2794 0.9906)
			)
			(stroke
				(width 0)
				(type default)
			)
			(fill no)
			(layer "B.CrtYd")
		)
		(fp_line
			(start -0.2794 -0.1016)
			(end 0.2794 -0.1016)
			(stroke
				(width 0.1)
				(type default)
			)
			(layer "B.Fab")
		)
		(fp_line
			(start -0.2794 0.9906)
			(end -0.2794 -0.1016)
			(stroke
				(width 0.1)
				(type default)
			)
			(layer "B.Fab")
		)
		(fp_line
			(start 0.2794 -0.1016)
			(end 0.2794 0.9906)
			(stroke
				(width 0.1)
				(type default)
			)
			(layer "B.Fab")
		)
		(fp_line
			(start 0.2794 0.9906)
			(end -0.2794 0.9906)
			(stroke
				(width 0.1)
				(type default)
			)
			(layer "B.Fab")
		)
		(pad "1" smd rect
			(at 0 0 180)
			(size 0.508 0.508)
			(layers "B.Cu" "B.Mask" "B.Paste")
			(net "SMB_VR_STBY_LVC3_SDA_R1")
		)
		(pad "2" smd rect
			(at 0 0.889 180)
			(size 0.508 0.508)
			(layers "B.Cu" "B.Mask" "B.Paste")
			(net "SMB_VR_STBY_LVC3_SDA")
		)
		(zone
			(layer "B.Cu")
			(hatch none 0.5)
			(connect_pads
				(clearance 0)
			)
			(min_thickness 0.25)
			(keepout
				(tracks allowed)
				(vias not_allowed)
				(pads allowed)
				(copperpour not_allowed)
				(footprints allowed)
			)
			(placement
				(enabled no)
				(sheetname "")
			)
			(fill
				(thermal_gap 0.5)
				(thermal_bridge_width 0.5)
				(island_removal_mode 0)
			)
			(polygon
				(pts
					(xy 398.6784 -88.0237) (xy 398.1704 -88.0237) (xy 398.1704 -87.6427) (xy 398.6784 -87.6427)
				)
			)
		)
		(zone
			(layer "B.Cu")
			(hatch none 0.5)
			(connect_pads
				(clearance 0)
			)
			(min_thickness 0.25)
			(keepout
				(tracks not_allowed)
				(vias allowed)
				(pads allowed)
				(copperpour not_allowed)
				(footprints allowed)
			)
			(placement
				(enabled no)
				(sheetname "")
			)
			(fill
				(thermal_gap 0.5)
				(thermal_bridge_width 0.5)
				(island_removal_mode 0)
			)
			(polygon
				(pts
					(xy 398.6784 -87.6427) (xy 398.1704 -87.6427) (xy 398.1704 -88.0237) (xy 398.6784 -88.0237)
				)
			)
		)
	)
	(footprint ""
		(layer "B.Cu")
		(at 442.663326 -147.663154 90)
		(property "Reference" "C25W97"
			(at 0.8382 -0.67818 90)
			(unlocked yes)
			(layer "B.SilkS")
			(effects
				(font
					(size 0.4064 0.254)
					(thickness 0.1524)
				)
				(justify left mirror)
			)
		)
		(property "Value" ""
			(at 0 0 90)
			(layer "B.Fab")
			(effects
				(font
					(size 1.27 1.27)
				)
				(justify mirror)
			)
		)
		(duplicate_pad_numbers_are_jumpers no)
		(fp_poly
			(pts
				(xy -0.3048 -0.1016) (xy -0.3048 0.9906) (xy 0.3048 0.9906) (xy 0.3048 -0.1016)
			)
			(stroke
				(width 0)
				(type default)
			)
			(fill no)
			(layer "B.CrtYd")
		)
		(fp_line
			(start 0.3048 -0.1016)
			(end 0.3048 0.9906)
			(stroke
				(width 0.1)
				(type default)
			)
			(layer "B.Fab")
		)
		(fp_line
			(start -0.3048 -0.1016)
			(end 0.3048 -0.1016)
			(stroke
				(width 0.1)
				(type default)
			)
			(layer "B.Fab")
		)
		(fp_line
			(start 0.3048 0.9906)
			(end -0.3048 0.9906)
			(stroke
				(width 0.1)
				(type default)
			)
			(layer "B.Fab")
		)
		(fp_line
			(start -0.3048 0.9906)
			(end -0.3048 -0.1016)
			(stroke
				(width 0.1)
				(type default)
			)
			(layer "B.Fab")
		)
		(pad "1" smd rect
			(at 0 0 270)
			(size 0.508 0.508)
			(layers "B.Cu" "B.Mask" "B.Paste")
			(net "P3V3_STBY")
		)
		(pad "2" smd rect
			(at 0 0.889 270)
			(size 0.508 0.508)
			(layers "B.Cu" "B.Mask" "B.Paste")
			(net "GND")
		)
		(zone
			(layer "B.Cu")
			(hatch none 0.5)
			(connect_pads
				(clearance 0)
			)
			(min_thickness 0.25)
			(keepout
				(tracks allowed)
				(vias not_allowed)
				(pads allowed)
				(copperpour not_allowed)
				(footprints allowed)
			)
			(placement
				(enabled no)
				(sheetname "")
			)
			(fill
				(thermal_gap 0.5)
				(thermal_bridge_width 0.5)
				(island_removal_mode 0)
			)
			(polygon
				(pts
					(xy 442.917326 -147.917154) (xy 442.917326 -147.409154) (xy 443.298326 -147.409154) (xy 443.298326 -147.917154)
				)
			)
		)
		(zone
			(layer "B.Cu")
			(hatch none 0.5)
			(connect_pads
				(clearance 0)
			)
			(min_thickness 0.25)
			(keepout
				(tracks not_allowed)
				(vias allowed)
				(pads allowed)
				(copperpour not_allowed)
				(footprints allowed)
			)
			(placement
				(enabled no)
				(sheetname "")
			)
			(fill
				(thermal_gap 0.5)
				(thermal_bridge_width 0.5)
				(island_removal_mode 0)
			)
			(polygon
				(pts
					(xy 443.298326 -147.917154) (xy 443.298326 -147.409154) (xy 442.917326 -147.409154) (xy 442.917326 -147.917154)
				)
			)
		)
	)
	(footprint ""
		(layer "B.Cu")
		(at 377.493022 -27.253438)
		(property "Reference" "RN8F5"
			(at 0.8382 -0.67818 0)
			(unlocked yes)
			(layer "B.SilkS")
			(effects
				(font
					(size 0.4064 0.254)
					(thickness 0.1524)
				)
				(justify left mirror)
			)
		)
		(property "Value" ""
			(at 0 0 0)
			(layer "B.Fab")
			(effects
				(font
					(size 1.27 1.27)
				)
				(justify mirror)
			)
		)
		(duplicate_pad_numbers_are_jumpers no)
		(fp_poly
			(pts
				(xy 0.2794 -0.1016) (xy -0.2794 -0.1016) (xy -0.2794 0.9906) (xy 0.2794 0.9906)
			)
			(stroke
				(width 0)
				(type default)
			)
			(fill no)
			(layer "B.CrtYd")
		)
		(fp_line
			(start -0.2794 -0.1016)
			(end 0.2794 -0.1016)
			(stroke
				(width 0.1)
				(type default)
			)
			(layer "B.Fab")
		)
		(fp_line
			(start -0.2794 0.9906)
			(end -0.2794 -0.1016)
			(stroke
				(width 0.1)
				(type default)
			)
			(layer "B.Fab")
		)
		(fp_line
			(start 0.2794 -0.1016)
			(end 0.2794 0.9906)
			(stroke
				(width 0.1)
				(type default)
			)
			(layer "B.Fab")
		)
		(fp_line
			(start 0.2794 0.9906)
			(end -0.2794 0.9906)
			(stroke
				(width 0.1)
				(type default)
			)
			(layer "B.Fab")
		)
		(pad "1" smd rect
			(at 0 0 180)
			(size 0.508 0.508)
			(layers "B.Cu" "B.Mask" "B.Paste")
			(net "SPI_BMC_BT_DI")
		)
		(pad "2" smd rect
			(at 0 0.889 180)
			(size 0.508 0.508)
			(layers "B.Cu" "B.Mask" "B.Paste")
			(net "SPI_TPM_BMC_DI_R")
		)
		(zone
			(layer "B.Cu")
			(hatch none 0.5)
			(connect_pads
				(clearance 0)
			)
			(min_thickness 0.25)
			(keepout
				(tracks allowed)
				(vias not_allowed)
				(pads allowed)
				(copperpour not_allowed)
				(footprints allowed)
			)
			(placement
				(enabled no)
				(sheetname "")
			)
			(fill
				(thermal_gap 0.5)
				(thermal_bridge_width 0.5)
				(island_removal_mode 0)
			)
			(polygon
				(pts
					(xy 377.747022 -26.999438) (xy 377.239022 -26.999438) (xy 377.239022 -26.618438) (xy 377.747022 -26.618438)
				)
			)
		)
		(zone
			(layer "B.Cu")
			(hatch none 0.5)
			(connect_pads
				(clearance 0)
			)
			(min_thickness 0.25)
			(keepout
				(tracks not_allowed)
				(vias allowed)
				(pads allowed)
				(copperpour not_allowed)
				(footprints allowed)
			)
			(placement
				(enabled no)
				(sheetname "")
			)
			(fill
				(thermal_gap 0.5)
				(thermal_bridge_width 0.5)
				(island_removal_mode 0)
			)
			(polygon
				(pts
					(xy 377.747022 -26.618438) (xy 377.239022 -26.618438) (xy 377.239022 -26.999438) (xy 377.747022 -26.999438)
				)
			)
		)
	)
	(footprint ""
		(layer "B.Cu")
		(at 354.36429 -77.915516 180)
		(property "Reference" "C3P32"
			(at 0 0 0)
			(layer "B.SilkS")
			(hide yes)
			(effects
				(font
					(size 1.27 1.27)
				)
				(justify mirror)
			)
		)
		(property "Value" ""
			(at 0 0 0)
			(layer "B.Fab")
			(effects
				(font
					(size 1.27 1.27)
				)
				(justify mirror)
			)
		)
		(duplicate_pad_numbers_are_jumpers no)
		(fp_poly
			(pts
				(xy -0.3048 -0.1016) (xy -0.3048 0.9906) (xy 0.3048 0.9906) (xy 0.3048 -0.1016)
			)
			(stroke
				(width 0)
				(type default)
			)
			(fill no)
			(layer "B.CrtYd")
		)
		(fp_line
			(start 0.3048 0.9906)
			(end -0.3048 0.9906)
			(stroke
				(width 0.1)
				(type default)
			)
			(layer "B.Fab")
		)
		(fp_line
			(start 0.3048 -0.1016)
			(end 0.3048 0.9906)
			(stroke
				(width 0.1)
				(type default)
			)
			(layer "B.Fab")
		)
		(fp_line
			(start -0.3048 0.9906)
			(end -0.3048 -0.1016)
			(stroke
				(width 0.1)
				(type default)
			)
			(layer "B.Fab")
		)
		(fp_line
			(start -0.3048 -0.1016)
			(end 0.3048 -0.1016)
			(stroke
				(width 0.1)
				(type default)
			)
			(layer "B.Fab")
		)
		(pad "1" smd rect
			(at 0 0)
			(size 0.508 0.508)
			(layers "B.Cu" "B.Mask" "B.Paste")
			(net "P3E_CPU0_PE1_SS_TXN<5>")
		)
		(pad "2" smd rect
			(at 0 0.889)
			(size 0.508 0.508)
			(layers "B.Cu" "B.Mask" "B.Paste")
			(net "P3E_CPU0_PE1_PCH_TXN<5>")
		)
		(zone
			(layer "B.Cu")
			(hatch none 0.5)
			(connect_pads
				(clearance 0)
			)
			(min_thickness 0.25)
			(keepout
				(tracks not_allowed)
				(vias allowed)
				(pads allowed)
				(copperpour not_allowed)
				(footprints allowed)
			)
			(placement
				(enabled no)
				(sheetname "")
			)
			(fill
				(thermal_gap 0.5)
				(thermal_bridge_width 0.5)
				(island_removal_mode 0)
			)
			(polygon
				(pts
					(xy 354.11029 -78.550516) (xy 354.61829 -78.550516) (xy 354.61829 -78.169516) (xy 354.11029 -78.169516)
				)
			)
		)
		(zone
			(layer "B.Cu")
			(hatch none 0.5)
			(connect_pads
				(clearance 0)
			)
			(min_thickness 0.25)
			(keepout
				(tracks allowed)
				(vias not_allowed)
				(pads allowed)
				(copperpour not_allowed)
				(footprints allowed)
			)
			(placement
				(enabled no)
				(sheetname "")
			)
			(fill
				(thermal_gap 0.5)
				(thermal_bridge_width 0.5)
				(island_removal_mode 0)
			)
			(polygon
				(pts
					(xy 354.11029 -78.169516) (xy 354.61829 -78.169516) (xy 354.61829 -78.550516) (xy 354.11029 -78.550516)
				)
			)
		)
	)
	(footprint ""
		(layer "B.Cu")
		(at 481.27666 -29.35732 -90)
		(property "Reference" "C2T25"
			(at 0 0 90)
			(layer "B.SilkS")
			(hide yes)
			(effects
				(font
					(size 1.27 1.27)
				)
				(justify mirror)
			)
		)
		(property "Value" ""
			(at 0 0 90)
			(layer "B.Fab")
			(effects
				(font
					(size 1.27 1.27)
				)
				(justify mirror)
			)
		)
		(duplicate_pad_numbers_are_jumpers no)
		(fp_poly
			(pts
				(xy -0.3048 -0.1016) (xy -0.3048 0.9906) (xy 0.3048 0.9906) (xy 0.3048 -0.1016)
			)
			(stroke
				(width 0)
				(type default)
			)
			(fill no)
			(layer "B.CrtYd")
		)
		(fp_line
			(start -0.3048 0.9906)
			(end -0.3048 -0.1016)
			(stroke
				(width 0.1)
				(type default)
			)
			(layer "B.Fab")
		)
		(fp_line
			(start 0.3048 0.9906)
			(end -0.3048 0.9906)
			(stroke
				(width 0.1)
				(type default)
			)
			(layer "B.Fab")
		)
		(fp_line
			(start -0.3048 -0.1016)
			(end 0.3048 -0.1016)
			(stroke
				(width 0.1)
				(type default)
			)
			(layer "B.Fab")
		)
		(fp_line
			(start 0.3048 -0.1016)
			(end 0.3048 0.9906)
			(stroke
				(width 0.1)
				(type default)
			)
			(layer "B.Fab")
		)
		(pad "1" smd rect
			(at 0 0 90)
			(size 0.508 0.508)
			(layers "B.Cu" "B.Mask" "B.Paste")
			(net "P3V3_STBY_MNG")
		)
		(pad "2" smd rect
			(at 0 0.889 90)
			(size 0.508 0.508)
			(layers "B.Cu" "B.Mask" "B.Paste")
			(net "GND")
		)
		(zone
			(layer "B.Cu")
			(hatch none 0.5)
			(connect_pads
				(clearance 0)
			)
			(min_thickness 0.25)
			(keepout
				(tracks not_allowed)
				(vias allowed)
				(pads allowed)
				(copperpour not_allowed)
				(footprints allowed)
			)
			(placement
				(enabled no)
				(sheetname "")
			)
			(fill
				(thermal_gap 0.5)
				(thermal_bridge_width 0.5)
				(island_removal_mode 0)
			)
			(polygon
				(pts
					(xy 480.64166 -29.10332) (xy 480.64166 -29.61132) (xy 481.02266 -29.61132) (xy 481.02266 -29.10332)
				)
			)
		)
		(zone
			(layer "B.Cu")
			(hatch none 0.5)
			(connect_pads
				(clearance 0)
			)
			(min_thickness 0.25)
			(keepout
				(tracks allowed)
				(vias not_allowed)
				(pads allowed)
				(copperpour not_allowed)
				(footprints allowed)
			)
			(placement
				(enabled no)
				(sheetname "")
			)
			(fill
				(thermal_gap 0.5)
				(thermal_bridge_width 0.5)
				(island_removal_mode 0)
			)
			(polygon
				(pts
					(xy 481.02266 -29.10332) (xy 481.02266 -29.61132) (xy 480.64166 -29.61132) (xy 480.64166 -29.10332)
				)
			)
		)
	)
	(footprint ""
		(layer "B.Cu")
		(at 253.392432 -149.8092 90)
		(property "Reference" "C5G62"
			(at -1.14681 0.76708 180)
			(unlocked yes)
			(layer "B.SilkS")
			(effects
				(font
					(size 0.7874 0.5842)
					(thickness 0.1524)
				)
				(justify mirror)
			)
		)
		(property "Value" ""
			(at 0 0 90)
			(layer "B.Fab")
			(effects
				(font
					(size 1.27 1.27)
				)
				(justify mirror)
			)
		)
		(duplicate_pad_numbers_are_jumpers no)
		(fp_rect
			(start -0.4953 -0.2032)
			(end 0.4953 1.6002)
			(stroke
				(width 0)
				(type default)
			)
			(fill no)
			(layer "B.CrtYd")
		)
		(fp_line
			(start 0.4953 -0.2032)
			(end -0.4953 -0.2032)
			(stroke
				(width 0.1)
				(type default)
			)
			(layer "B.Fab")
		)
		(fp_line
			(start -0.4953 -0.2032)
			(end -0.4953 1.6002)
			(stroke
				(width 0.1)
				(type default)
			)
			(layer "B.Fab")
		)
		(fp_line
			(start 0.4953 1.6002)
			(end 0.4953 -0.2032)
			(stroke
				(width 0.1)
				(type default)
			)
			(layer "B.Fab")
		)
		(fp_line
			(start -0.4953 1.6002)
			(end 0.4953 1.6002)
			(stroke
				(width 0.1)
				(type default)
			)
			(layer "B.Fab")
		)
		(pad "1" smd rect
			(at 0 0 270)
			(size 0.762 0.889)
			(layers "B.Cu" "B.Mask" "B.Paste")
			(net "PVDDQ_DEF")
		)
		(pad "2" smd rect
			(at 0 1.397 270)
			(size 0.762 0.889)
			(layers "B.Cu" "B.Mask" "B.Paste")
			(net "GND")
		)
		(zone
			(layer "B.Cu")
			(hatch none 0.5)
			(connect_pads
				(clearance 0)
			)
			(min_thickness 0.25)
			(keepout
				(tracks not_allowed)
				(vias allowed)
				(pads allowed)
				(copperpour not_allowed)
				(footprints allowed)
			)
			(placement
				(enabled no)
				(sheetname "")
			)
			(fill
				(thermal_gap 0.5)
				(thermal_bridge_width 0.5)
				(island_removal_mode 0)
			)
			(polygon
				(pts
					(xy 253.836932 -149.4282) (xy 254.344932 -149.4282) (xy 254.344932 -150.1902) (xy 253.836932 -150.1902)
				)
			)
		)
	)
	(footprint ""
		(layer "B.Cu")
		(at 360.2228 -141.833092 -90)
		(property "Reference" "CF18"
			(at 0 0 90)
			(layer "B.SilkS")
			(hide yes)
			(effects
				(font
					(size 1.27 1.27)
				)
				(justify mirror)
			)
		)
		(property "Value" "*"
			(at -1.1811 -2.8194 270)
			(unlocked yes)
			(layer "B.Fab")
			(hide yes)
			(effects
				(font
					(size 1.27 1.016)
					(thickness 0.1524)
				)
				(justify mirror)
			)
		)
		(property "Device Type" "SC22P50V2JN-4GP_SMD-BCG-SC22P5A"
			(at -1.1811 -4.3434 270)
			(unlocked yes)
			(layer "B.Fab")
			(hide yes)
			(effects
				(font
					(size 1.27 1.016)
					(thickness 0.1524)
				)
				(justify mirror)
			)
		)
		(duplicate_pad_numbers_are_jumpers no)
		(fp_rect
			(start 0.4318 0.9525)
			(end -0.4318 -0.9525)
			(stroke
				(width 0)
				(type default)
			)
			(fill no)
			(layer "B.CrtYd")
		)
		(fp_rect
			(start 0.4318 0.9525)
			(end -0.4318 -0.9525)
			(stroke
				(width 0)
				(type default)
			)
			(fill no)
			(layer "B.Fab")
		)
		(pad "1" smd custom
			(at 0 -0.4445 90)
			(size 0.1524 0.1524)
			(layers "B.Cu" "B.Mask" "B.Paste")
			(net "VR_PVDDQ_DEF_AIREF2")
			(options
				(clearance outline)
				(anchor circle)
			)
			(primitives
				(gr_poly
					(pts
						(arc
							(start 0.3048 0.2032)
							(mid 0.275042 0.275042)
							(end 0.2032 0.3048)
						)
						(arc
							(start -0.2032 0.3048)
							(mid -0.275042 0.275042)
							(end -0.3048 0.2032)
						)
						(arc
							(start -0.3048 -0.2032)
							(mid -0.275042 -0.275042)
							(end -0.2032 -0.3048)
						)
						(arc
							(start 0.2032 -0.3048)
							(mid 0.275042 -0.275042)
							(end 0.3048 -0.2032)
						)
					)
					(width 0)
					(fill yes)
				)
			)
		)
		(pad "2" smd custom
			(at 0 0.4445 90)
			(size 0.1524 0.1524)
			(layers "B.Cu" "B.Mask" "B.Paste")
			(net "ISENSE_PVDDQ_DEF_PH2_IMON")
			(options
				(clearance outline)
				(anchor circle)
			)
			(primitives
				(gr_poly
					(pts
						(arc
							(start 0.3048 0.2032)
							(mid 0.275042 0.275042)
							(end 0.2032 0.3048)
						)
						(arc
							(start -0.2032 0.3048)
							(mid -0.275042 0.275042)
							(end -0.3048 0.2032)
						)
						(arc
							(start -0.3048 -0.2032)
							(mid -0.275042 -0.275042)
							(end -0.2032 -0.3048)
						)
						(arc
							(start 0.2032 -0.3048)
							(mid 0.275042 -0.275042)
							(end 0.3048 -0.2032)
						)
					)
					(width 0)
					(fill yes)
				)
			)
		)
	)
)
